(kicad_pcb
	(version 20260206)
	(generator "pcbnew")
	(generator_version "10.0")
	(general
		(thickness 1.6)
		(legacy_teardrops no)
	)
	(paper "A4")
	(title_block
		(title "v2-tray-backplane — ms_tbp_v2.brd")
		(comment 1 "Open CloudServer (Microsoft) / footprints 99-104 of 164")
	)
	(layers
		(0 "F.Cu" signal "TOP")
		(4 "In1.Cu" signal "LYR2")
		(6 "In2.Cu" signal "LYR3")
		(8 "In3.Cu" signal "LYR4")
		(10 "In4.Cu" signal "LYR5")
		(12 "In5.Cu" signal "LYR6")
		(14 "In6.Cu" signal "LYR7")
		(2 "B.Cu" signal "BOTTOM")
		(9 "F.Adhes" user "F.Adhesive")
		(11 "B.Adhes" user "B.Adhesive")
		(13 "F.Paste" user "Package Geometry/Pastemask Top")
		(15 "B.Paste" user "Package Geometry/Pastemask Bottom")
		(5 "F.SilkS" user "Ref Des/Silkscreen Top")
		(7 "B.SilkS" user "Ref Des/Silkscreen Bottom")
		(1 "F.Mask" user "Board Geometry/Soldermask Top")
		(3 "B.Mask" user "Board Geometry/Soldermask Bottom")
		(17 "Dwgs.User" user "User.Drawings")
		(19 "Cmts.User" user "User.Comments")
		(21 "Eco1.User" user "User.Eco1")
		(23 "Eco2.User" user "User.Eco2")
		(25 "Edge.Cuts" user "Board Geometry/Outline")
		(27 "Margin" user)
		(31 "F.CrtYd" user "Package Geometry/Place Bound Top")
		(29 "B.CrtYd" user "Package Geometry/Place Bound Bottom")
		(35 "F.Fab" user "Ref Des/Assembly Top")
		(33 "B.Fab" user "Ref Des/Assembly Bottom")
	)
	(footprint ""
		(layer "F.Cu")
		(at -284.563401 44.488202 180)
		(property "Reference" "C8"
			(at 2.126399 0.025502 0)
			(unlocked yes)
			(layer "F.SilkS")
			(effects
				(font
					(size 0.762 0.5334)
					(thickness 0.1016)
				)
			)
		)
		(property "Value" ""
			(at 0 0 180)
			(layer "F.Fab")
			(effects
				(font
					(size 1.27 1.27)
				)
			)
		)
		(duplicate_pad_numbers_are_jumpers no)
		(fp_poly
			(pts
				(xy -0.9993 0.504) (xy -0.9993 -0.503999) (xy 0.999299 -0.503999) (xy 0.999299 0.504)
			)
			(stroke
				(width 0)
				(type default)
			)
			(fill no)
			(layer "F.CrtYd")
		)
		(fp_line
			(start 0.499999 0.25)
			(end -0.499999 0.25)
			(stroke
				(width 0.1)
				(type default)
			)
			(layer "F.Fab")
		)
		(fp_line
			(start 0.499999 -0.249999)
			(end 0.499999 0.25)
			(stroke
				(width 0.1)
				(type default)
			)
			(layer "F.Fab")
		)
		(fp_line
			(start -0.499999 0.25)
			(end -0.499999 -0.249999)
			(stroke
				(width 0.1)
				(type default)
			)
			(layer "F.Fab")
		)
		(fp_line
			(start -0.499999 -0.249999)
			(end 0.499999 -0.249999)
			(stroke
				(width 0.1)
				(type default)
			)
			(layer "F.Fab")
		)
		(pad "1" smd rect
			(at -0.4572 0 270)
			(size 0.508 0.5842)
			(layers "F.Cu" "F.Mask" "F.Paste")
			(net "P3V3_10G_B1_VCCR")
		)
		(pad "2" smd rect
			(at 0.4572 0 270)
			(size 0.508 0.5842)
			(layers "F.Cu" "F.Mask" "F.Paste")
			(net "GND")
		)
	)
	(footprint ""
		(layer "F.Cu")
		(at -296.145801 6.845402)
		(property "Reference" "R22"
			(at 3.052661 0.258978 0)
			(unlocked yes)
			(layer "F.SilkS")
			(effects
				(font
					(size 0.762 0.5334)
					(thickness 0.1016)
				)
			)
		)
		(property "Value" ""
			(at 0 0 0)
			(layer "F.Fab")
			(effects
				(font
					(size 1.27 1.27)
				)
			)
		)
		(duplicate_pad_numbers_are_jumpers no)
		(fp_line
			(start 0 -0.381)
			(end 0 0.381)
			(stroke
				(width 0.127)
				(type default)
			)
			(layer "F.SilkS")
		)
		(fp_poly
			(pts
				(xy 1.255601 0.656399) (xy -1.255601 0.656399) (xy -1.255601 -0.6564) (xy 1.255601 -0.6564)
			)
			(stroke
				(width 0)
				(type default)
			)
			(fill no)
			(layer "F.CrtYd")
		)
		(fp_line
			(start -0.800001 -0.4)
			(end -0.800001 0.399999)
			(stroke
				(width 0.1)
				(type default)
			)
			(layer "F.Fab")
		)
		(fp_line
			(start -0.800001 0.399999)
			(end 0.800001 0.399999)
			(stroke
				(width 0.1)
				(type default)
			)
			(layer "F.Fab")
		)
		(fp_line
			(start 0.800001 -0.4)
			(end -0.800001 -0.4)
			(stroke
				(width 0.1)
				(type default)
			)
			(layer "F.Fab")
		)
		(fp_line
			(start 0.800001 0.399999)
			(end 0.800001 -0.4)
			(stroke
				(width 0.1)
				(type default)
			)
			(layer "F.Fab")
		)
		(pad "1" smd rect
			(at -0.650001 0)
			(size 0.7112 0.8128)
			(layers "F.Cu" "F.Mask" "F.Paste")
			(net "P3V3_B1_QSFP")
		)
		(pad "2" smd rect
			(at 0.650001 0 180)
			(size 0.7112 0.8128)
			(layers "F.Cu" "F.Mask" "F.Paste")
			(net "ETH10G_B1_RS0")
		)
	)
	(footprint ""
		(layer "F.Cu")
		(at -61.750001 32.059999 180)
		(property "Reference" "J17"
			(at 7.231319 -7.183001 0)
			(unlocked yes)
			(layer "F.SilkS")
			(effects
				(font
					(size 0.762 0.5334)
					(thickness 0.1016)
				)
			)
		)
		(property "Value" ""
			(at 0 0 180)
			(layer "F.Fab")
			(effects
				(font
					(size 1.27 1.27)
				)
			)
		)
		(duplicate_pad_numbers_are_jumpers no)
		(fp_line
			(start 5.499999 3.85)
			(end 4.500001 3.85)
			(stroke
				(width 0.127)
				(type default)
			)
			(layer "F.SilkS")
		)
		(fp_line
			(start 5.499999 1.499999)
			(end 5.499999 3.85)
			(stroke
				(width 0.127)
				(type default)
			)
			(layer "F.SilkS")
		)
		(fp_line
			(start 5.499999 -1.5)
			(end 5.499999 -3.85)
			(stroke
				(width 0.127)
				(type default)
			)
			(layer "F.SilkS")
		)
		(fp_line
			(start 5.499999 -3.85)
			(end 4 -3.85)
			(stroke
				(width 0.127)
				(type default)
			)
			(layer "F.SilkS")
		)
		(fp_line
			(start -4 3.85)
			(end -5.499999 3.85)
			(stroke
				(width 0.127)
				(type default)
			)
			(layer "F.SilkS")
		)
		(fp_line
			(start -5.499999 3.85)
			(end -5.499999 1.499999)
			(stroke
				(width 0.127)
				(type default)
			)
			(layer "F.SilkS")
		)
		(fp_line
			(start -5.499999 -1.5)
			(end -5.499999 -2.85)
			(stroke
				(width 0.127)
				(type default)
			)
			(layer "F.SilkS")
		)
		(fp_line
			(start -5.499999 -2.85)
			(end -4.500001 -3.85)
			(stroke
				(width 0.127)
				(type default)
			)
			(layer "F.SilkS")
		)
		(fp_poly
			(pts
				(xy -4.154 5.603301) (xy -4.154 4.349999) (xy -6.000001 4.349999) (xy -6.000001 -4.349999) (xy -4.553999 -4.349999)
				(xy -4.553999 -5.603301) (xy 4.154 -5.603301) (xy 4.154 -4.349999) (xy 6.000001 -4.349999) (xy 6.000001 4.349999)
				(xy 4.553999 4.349999) (xy 4.553999 5.603301)
			)
			(stroke
				(width 0)
				(type default)
			)
			(fill no)
			(layer "F.CrtYd")
		)
		(fp_line
			(start 5.499999 3.85)
			(end -5.499999 3.85)
			(stroke
				(width 0.1)
				(type default)
			)
			(layer "F.Fab")
		)
		(fp_line
			(start 5.499999 -3.85)
			(end 5.499999 3.85)
			(stroke
				(width 0.1)
				(type default)
			)
			(layer "F.Fab")
		)
		(fp_line
			(start -4.500001 -3.85)
			(end 5.499999 -3.85)
			(stroke
				(width 0.1)
				(type default)
			)
			(layer "F.Fab")
		)
		(fp_line
			(start -5.499999 3.85)
			(end -5.499999 -2.85)
			(stroke
				(width 0.1)
				(type default)
			)
			(layer "F.Fab")
		)
		(fp_line
			(start -5.499999 -2.85)
			(end -4.500001 -3.85)
			(stroke
				(width 0.1)
				(type default)
			)
			(layer "F.Fab")
		)
		(fp_text user "10"
			(at 4.968179 4.625459 0)
			(unlocked yes)
			(layer "F.SilkS")
			(effects
				(font
					(size 0.762 0.5334)
					(thickness 0.1016)
				)
			)
		)
		(fp_text user "11"
			(at 4.871659 -4.589661 0)
			(unlocked yes)
			(layer "F.SilkS")
			(effects
				(font
					(size 0.762 0.5334)
					(thickness 0.1016)
				)
			)
		)
		(fp_text user "*"
			(at -4.600001 4.571448 0)
			(unlocked yes)
			(layer "F.SilkS")
			(effects
				(font
					(size 0.381 0.381)
					(thickness 0.381)
				)
			)
		)
		(fp_text user "20"
			(at -4.935281 -4.541401 0)
			(unlocked yes)
			(layer "F.SilkS")
			(effects
				(font
					(size 0.762 0.5334)
					(thickness 0.1016)
				)
			)
		)
		(pad "" np_thru_hole circle
			(at -4.800001 0 180)
			(size 1.27 1.27)
			(drill 1.6002)
			(layers "*.Cu" "*.Mask")
		)
		(pad "" np_thru_hole circle
			(at 4.800001 0 180)
			(size 1.27 1.27)
			(drill 1.6002)
			(layers "*.Cu" "*.Mask")
		)
		(pad "1" smd oval
			(at -3.400001 4.099999 180)
			(size 0.508 2.0066)
			(layers "F.Cu" "F.Mask" "F.Paste")
			(net "GND")
		)
		(pad "2" smd oval
			(at -2.6 4.099999 180)
			(size 0.508 2.0066)
			(layers "F.Cu" "F.Mask" "F.Paste")
			(net "ETH10G_B2_TX_FAULT")
		)
		(pad "3" smd oval
			(at -1.799999 4.099999 180)
			(size 0.508 2.0066)
			(layers "F.Cu" "F.Mask" "F.Paste")
			(net "ETH10G_B2_TX_DIS")
		)
		(pad "4" smd oval
			(at -1.000001 4.099999 180)
			(size 0.508 2.0066)
			(layers "F.Cu" "F.Mask" "F.Paste")
			(net "ETH10G_B2_SDA")
		)
		(pad "5" smd oval
			(at -0.2 4.099999 180)
			(size 0.508 2.0066)
			(layers "F.Cu" "F.Mask" "F.Paste")
			(net "ETH10G_B2_SCL")
		)
		(pad "6" smd oval
			(at 0.599999 4.099999 180)
			(size 0.508 2.0066)
			(layers "F.Cu" "F.Mask" "F.Paste")
			(net "ETH10G_B2_MOD_ABS")
		)
		(pad "7" smd oval
			(at 1.4 4.099999 180)
			(size 0.508 2.0066)
			(layers "F.Cu" "F.Mask" "F.Paste")
			(net "ETH10G_B2_RS0")
		)
		(pad "8" smd oval
			(at 2.200001 4.099999 180)
			(size 0.508 2.0066)
			(layers "F.Cu" "F.Mask" "F.Paste")
			(net "ETH10G_B2_RX_LOS")
		)
		(pad "9" smd oval
			(at 2.999999 4.099999 180)
			(size 0.508 2.0066)
			(layers "F.Cu" "F.Mask" "F.Paste")
			(net "ETH10G_B2_RS1")
		)
		(pad "10" smd oval
			(at 3.8 4.099999 180)
			(size 0.508 2.0066)
			(layers "F.Cu" "F.Mask" "F.Paste")
			(net "GND")
		)
		(pad "11" smd oval
			(at 3.400001 -4.099999 180)
			(size 0.508 2.0066)
			(layers "F.Cu" "F.Mask" "F.Paste")
			(net "GND")
		)
		(pad "12" smd oval
			(at 2.6 -4.099999 180)
			(size 0.508 2.0066)
			(layers "F.Cu" "F.Mask" "F.Paste")
			(net "ETH10G_B2_RXN")
		)
		(pad "13" smd oval
			(at 1.799999 -4.099999 180)
			(size 0.508 2.0066)
			(layers "F.Cu" "F.Mask" "F.Paste")
			(net "ETH10G_B2_RXP")
		)
		(pad "14" smd oval
			(at 1.000001 -4.099999 180)
			(size 0.508 2.0066)
			(layers "F.Cu" "F.Mask" "F.Paste")
			(net "GND")
		)
		(pad "15" smd oval
			(at 0.2 -4.099999 180)
			(size 0.508 2.0066)
			(layers "F.Cu" "F.Mask" "F.Paste")
			(net "P3V3_10G_B2_VCCR")
		)
		(pad "16" smd oval
			(at -0.599999 -4.099999 180)
			(size 0.508 2.0066)
			(layers "F.Cu" "F.Mask" "F.Paste")
			(net "P3V3_10G_B2_VCCT")
		)
		(pad "17" smd oval
			(at -1.4 -4.099999 180)
			(size 0.508 2.0066)
			(layers "F.Cu" "F.Mask" "F.Paste")
			(net "GND")
		)
		(pad "18" smd oval
			(at -2.200001 -4.099999 180)
			(size 0.508 2.0066)
			(layers "F.Cu" "F.Mask" "F.Paste")
			(net "ETH10G_B2_TXP")
		)
		(pad "19" smd oval
			(at -2.999999 -4.099999 180)
			(size 0.508 2.0066)
			(layers "F.Cu" "F.Mask" "F.Paste")
			(net "ETH10G_B2_TXN")
		)
		(pad "20" smd oval
			(at -3.8 -4.099999 180)
			(size 0.508 2.0066)
			(layers "F.Cu" "F.Mask" "F.Paste")
			(net "GND")
		)
		(zone
			(layers "F.Cu" "B.Cu" "In1.Cu" "In2.Cu" "In3.Cu" "In4.Cu" "In5.Cu" "In6.Cu")
			(hatch none 0.5)
			(connect_pads
				(clearance 0)
			)
			(min_thickness 0.25)
			(keepout
				(tracks not_allowed)
				(vias allowed)
				(pads allowed)
				(copperpour not_allowed)
				(footprints allowed)
			)
			(placement
				(enabled no)
				(sheetname "")
			)
			(fill
				(thermal_gap 0.5)
				(thermal_bridge_width 0.5)
				(island_removal_mode 0)
			)
			(polygon
				(pts
					(arc
						(start -67.730002 32.059999)
						(mid -65.370002 32.059999)
						(end -67.730002 32.059999)
					)
				)
			)
		)
		(zone
			(layers "F.Cu" "B.Cu" "In1.Cu" "In2.Cu" "In3.Cu" "In4.Cu" "In5.Cu" "In6.Cu")
			(hatch none 0.5)
			(connect_pads
				(clearance 0)
			)
			(min_thickness 0.25)
			(keepout
				(tracks not_allowed)
				(vias allowed)
				(pads allowed)
				(copperpour not_allowed)
				(footprints allowed)
			)
			(placement
				(enabled no)
				(sheetname "")
			)
			(fill
				(thermal_gap 0.5)
				(thermal_bridge_width 0.5)
				(island_removal_mode 0)
			)
			(polygon
				(pts
					(arc
						(start -58.130001 32.059999)
						(mid -55.769999 32.059999)
						(end -58.130001 32.059999)
					)
				)
			)
		)
	)
	(footprint ""
		(layer "F.Cu")
		(at -268.224 2.921 -90)
		(property "Reference" "C32"
			(at 1.88976 0.14478 90)
			(unlocked yes)
			(layer "F.SilkS")
			(effects
				(font
					(size 0.762 0.5334)
					(thickness 0.1016)
				)
			)
		)
		(property "Value" ""
			(at 0 0 270)
			(layer "F.Fab")
			(effects
				(font
					(size 1.27 1.27)
				)
			)
		)
		(duplicate_pad_numbers_are_jumpers no)
		(fp_poly
			(pts
				(xy -0.999299 0.504) (xy -0.999299 -0.503999) (xy 0.9993 -0.503999) (xy 0.9993 0.504)
			)
			(stroke
				(width 0)
				(type default)
			)
			(fill no)
			(layer "F.CrtYd")
		)
		(fp_line
			(start -0.499999 0.25)
			(end -0.499999 -0.249999)
			(stroke
				(width 0.1)
				(type default)
			)
			(layer "F.Fab")
		)
		(fp_line
			(start 0.499999 0.25)
			(end -0.499999 0.25)
			(stroke
				(width 0.1)
				(type default)
			)
			(layer "F.Fab")
		)
		(fp_line
			(start -0.499999 -0.249999)
			(end 0.499999 -0.249999)
			(stroke
				(width 0.1)
				(type default)
			)
			(layer "F.Fab")
		)
		(fp_line
			(start 0.499999 -0.249999)
			(end 0.499999 0.25)
			(stroke
				(width 0.1)
				(type default)
			)
			(layer "F.Fab")
		)
		(pad "1" smd rect
			(at -0.4572 0)
			(size 0.508 0.5842)
			(layers "F.Cu" "F.Mask" "F.Paste")
			(net "P3V3_40G_B1_VCC_RX")
		)
		(pad "2" smd rect
			(at 0.4572 0)
			(size 0.508 0.5842)
			(layers "F.Cu" "F.Mask" "F.Paste")
			(net "GND")
		)
	)
	(footprint ""
		(layer "F.Cu")
		(at -75.329199 2.476398 180)
		(property "Reference" "R52"
			(at -3.066199 0.025298 0)
			(unlocked yes)
			(layer "F.SilkS")
			(effects
				(font
					(size 0.762 0.5334)
					(thickness 0.1016)
				)
			)
		)
		(property "Value" ""
			(at 0 0 180)
			(layer "F.Fab")
			(effects
				(font
					(size 1.27 1.27)
				)
			)
		)
		(duplicate_pad_numbers_are_jumpers no)
		(fp_line
			(start 0 -0.381)
			(end 0 0.381)
			(stroke
				(width 0.127)
				(type default)
			)
			(layer "F.SilkS")
		)
		(fp_poly
			(pts
				(xy 1.255601 0.656399) (xy -1.255601 0.656399) (xy -1.255601 -0.6564) (xy 1.255601 -0.6564)
			)
			(stroke
				(width 0)
				(type default)
			)
			(fill no)
			(layer "F.CrtYd")
		)
		(fp_line
			(start 0.800001 0.399999)
			(end 0.800001 -0.4)
			(stroke
				(width 0.1)
				(type default)
			)
			(layer "F.Fab")
		)
		(fp_line
			(start 0.800001 -0.4)
			(end -0.800001 -0.4)
			(stroke
				(width 0.1)
				(type default)
			)
			(layer "F.Fab")
		)
		(fp_line
			(start -0.800001 0.399999)
			(end 0.800001 0.399999)
			(stroke
				(width 0.1)
				(type default)
			)
			(layer "F.Fab")
		)
		(fp_line
			(start -0.800001 -0.4)
			(end -0.800001 0.399999)
			(stroke
				(width 0.1)
				(type default)
			)
			(layer "F.Fab")
		)
		(pad "1" smd rect
			(at -0.650001 0 180)
			(size 0.7112 0.8128)
			(layers "F.Cu" "F.Mask" "F.Paste")
			(net "P3V3_B2_QSFP")
		)
		(pad "2" smd rect
			(at 0.650001 0)
			(size 0.7112 0.8128)
			(layers "F.Cu" "F.Mask" "F.Paste")
			(net "ETH10G_B2_RS1")
		)
	)
	(footprint ""
		(layer "F.Cu")
		(at -110.8456 10.4394)
		(property "Reference" "R69"
			(at 3.1496 0.0127 0)
			(unlocked yes)
			(layer "F.SilkS")
			(effects
				(font
					(size 0.762 0.5334)
					(thickness 0.1016)
				)
			)
		)
		(property "Value" ""
			(at 0 0 0)
			(layer "F.Fab")
			(effects
				(font
					(size 1.27 1.27)
				)
			)
		)
		(duplicate_pad_numbers_are_jumpers no)
		(fp_line
			(start 0 -0.381)
			(end 0 0.381)
			(stroke
				(width 0.127)
				(type default)
			)
			(layer "F.SilkS")
		)
		(fp_poly
			(pts
				(xy 1.255601 0.6564) (xy -1.255601 0.6564) (xy -1.255601 -0.656399) (xy 1.255601 -0.656399)
			)
			(stroke
				(width 0)
				(type default)
			)
			(fill no)
			(layer "F.CrtYd")
		)
		(fp_line
			(start -0.800001 -0.399999)
			(end -0.800001 0.399999)
			(stroke
				(width 0.1)
				(type default)
			)
			(layer "F.Fab")
		)
		(fp_line
			(start -0.800001 0.399999)
			(end 0.800001 0.399999)
			(stroke
				(width 0.1)
				(type default)
			)
			(layer "F.Fab")
		)
		(fp_line
			(start 0.800001 -0.399999)
			(end -0.800001 -0.399999)
			(stroke
				(width 0.1)
				(type default)
			)
			(layer "F.Fab")
		)
		(fp_line
			(start 0.800001 0.399999)
			(end 0.800001 -0.399999)
			(stroke
				(width 0.1)
				(type default)
			)
			(layer "F.Fab")
		)
		(pad "1" smd rect
			(at -0.650001 0)
			(size 0.7112 0.8128)
			(layers "F.Cu" "F.Mask" "F.Paste")
			(net "P3V3_B2_QSFP")
		)
		(pad "2" smd rect
			(at 0.650001 0 180)
			(size 0.7112 0.8128)
			(layers "F.Cu" "F.Mask" "F.Paste")
			(net "ETH40G_B2_RESET_N")
		)
	)
)
